# S9S_MB_2U (Grand Teton) — schematic netlist excerpt (pin names and nets, part order shuffled) for the footprints in the layout excerpt that follows; sources: Cadence DE-HDL packaged netlist, KiCad conversion of 03242023_DA0F0TMBIJ0_F0T_Motherboard_J_brd_V01_OCP.brd

C1002  Q_CAP  10UF 6.3V 20% X6S  pkg C0402  page 74 : A = PVCCIN_CPU0 ; B = GND
PR3990  Q_RES  2K 0.1% CHIP  pkg 0402LF  page 303 : A = HSC_IMON ; B = AGND_HSC

(kicad_pcb
	(version 20260206)
	(generator "pcbnew")
	(generator_version "10.0")
	(general
		(thickness 1.6)
		(legacy_teardrops no)
	)
	(paper "A4")
	(title_block
		(title "03242023_DA0F0TMBIJ0_F0T_Motherboard_J_brd_V01_OCP.brd")
		(comment 1 "Grand Teton / footprints 4082-4083 of 6105")
	)
	(layers
		(0 "F.Cu" signal "TOP")
		(4 "In1.Cu" signal "GND")
		(6 "In2.Cu" signal "IN1")
		(8 "In3.Cu" signal "GND1")
		(10 "In4.Cu" signal "IN2")
		(12 "In5.Cu" signal "GND2")
		(14 "In6.Cu" signal "IN3")
		(16 "In7.Cu" signal "GND3")
		(18 "In8.Cu" signal "VCC")
		(20 "In9.Cu" signal "VCC1")
		(22 "In10.Cu" signal "GND4")
		(24 "In11.Cu" signal "IN4")
		(26 "In12.Cu" signal "GND5")
		(28 "In13.Cu" signal "IN5")
		(30 "In14.Cu" signal "GND6")
		(32 "In15.Cu" signal "IN6")
		(34 "In16.Cu" signal "GND7")
		(2 "B.Cu" signal "BOTTOM")
		(9 "F.Adhes" user "F.Adhesive")
		(11 "B.Adhes" user "B.Adhesive")
		(13 "F.Paste" user "Package Geometry/Pastemask Top")
		(15 "B.Paste" user "Package Geometry/Pastemask Bottom")
		(5 "F.SilkS" user "Ref Des/Silkscreen Top")
		(7 "B.SilkS" user "Ref Des/Silkscreen Bottom")
		(1 "F.Mask" user "Board Geometry/Soldermask Top")
		(3 "B.Mask" user "Board Geometry/Soldermask Bottom")
		(17 "Dwgs.User" user "User.Drawings")
		(19 "Cmts.User" user "User.Comments")
		(21 "Eco1.User" user "User.Eco1")
		(23 "Eco2.User" user "User.Eco2")
		(25 "Edge.Cuts" user "Board Geometry/Outline")
		(27 "Margin" user)
		(31 "F.CrtYd" user "Package Geometry/Place Bound Top")
		(29 "B.CrtYd" user "Package Geometry/Place Bound Bottom")
		(35 "F.Fab" user "Ref Des/Assembly Top")
		(33 "B.Fab" user "Ref Des/Assembly Bottom")
	)
	(footprint ""
		(layer "F.Cu")
		(at 216.065608 -402.791422 180)
		(property "Reference" "PR3990"
			(at 0 0 180)
			(layer "F.SilkS")
			(hide yes)
			(effects
				(font
					(size 1.27 1.27)
				)
			)
		)
		(property "Value" ""
			(at 0 0 180)
			(layer "F.Fab")
			(effects
				(font
					(size 1.27 1.27)
				)
			)
		)
		(duplicate_pad_numbers_are_jumpers no)
		(fp_line
			(start 0.7874 0.4064)
			(end -0.7874 0.4064)
			(stroke
				(width 0.1524)
				(type default)
			)
			(layer "F.SilkS")
		)
		(fp_line
			(start 0.7874 -0.4064)
			(end 0.7874 0.4064)
			(stroke
				(width 0.1524)
				(type default)
			)
			(layer "F.SilkS")
		)
		(fp_line
			(start -0.7874 0.4064)
			(end -0.7874 -0.4064)
			(stroke
				(width 0.1524)
				(type default)
			)
			(layer "F.SilkS")
		)
		(fp_line
			(start -0.7874 -0.4064)
			(end 0.7874 -0.4064)
			(stroke
				(width 0.1524)
				(type default)
			)
			(layer "F.SilkS")
		)
		(fp_line
			(start 0.67945 0.3048)
			(end 0.120396 0.3048)
			(stroke
				(width 0.1)
				(type default)
			)
			(layer "F.Fab")
		)
		(fp_line
			(start 0.67945 -0.3048)
			(end 0.67945 0.3048)
			(stroke
				(width 0.1)
				(type default)
			)
			(layer "F.Fab")
		)
		(fp_line
			(start 0.12065 -0.2794)
			(end 0.12065 -0.3048)
			(stroke
				(width 0.1)
				(type default)
			)
			(layer "F.Fab")
		)
		(fp_line
			(start 0.12065 -0.3048)
			(end 0.67945 -0.3048)
			(stroke
				(width 0.1)
				(type default)
			)
			(layer "F.Fab")
		)
		(fp_line
			(start 0.120396 0.3048)
			(end 0.120396 0.2794)
			(stroke
				(width 0.1)
				(type default)
			)
			(layer "F.Fab")
		)
		(fp_line
			(start 0.120396 0.2794)
			(end -0.12065 0.2794)
			(stroke
				(width 0.1)
				(type default)
			)
			(layer "F.Fab")
		)
		(fp_line
			(start -0.12065 0.3048)
			(end -0.67945 0.3048)
			(stroke
				(width 0.1)
				(type default)
			)
			(layer "F.Fab")
		)
		(fp_line
			(start -0.12065 0.2794)
			(end -0.12065 0.3048)
			(stroke
				(width 0.1)
				(type default)
			)
			(layer "F.Fab")
		)
		(fp_line
			(start -0.12065 -0.2794)
			(end 0.12065 -0.2794)
			(stroke
				(width 0.1)
				(type default)
			)
			(layer "F.Fab")
		)
		(fp_line
			(start -0.12065 -0.305054)
			(end -0.12065 -0.2794)
			(stroke
				(width 0.1)
				(type default)
			)
			(layer "F.Fab")
		)
		(fp_line
			(start -0.67945 0.3048)
			(end -0.67945 -0.305054)
			(stroke
				(width 0.1)
				(type default)
			)
			(layer "F.Fab")
		)
		(fp_line
			(start -0.67945 -0.305054)
			(end -0.12065 -0.305054)
			(stroke
				(width 0.1)
				(type default)
			)
			(layer "F.Fab")
		)
		(pad "1" smd circle
			(at -0.40005 0 180)
			(size 0 0)
			(layers "F.Cu" "F.Mask" "F.Paste")
			(net "HSC_IMON")
		)
		(pad "2" smd circle
			(at 0.40005 0 180)
			(size 0 0)
			(layers "F.Cu" "F.Mask" "F.Paste")
			(net "AGND_HSC")
		)
	)
	(footprint ""
		(layer "F.Cu")
		(at 353.248214 -252.956314 -90)
		(property "Reference" "C1002"
			(at 0 0 270)
			(layer "F.SilkS")
			(hide yes)
			(effects
				(font
					(size 1.27 1.27)
				)
			)
		)
		(property "Value" ""
			(at 0 0 270)
			(layer "F.Fab")
			(effects
				(font
					(size 1.27 1.27)
				)
			)
		)
		(duplicate_pad_numbers_are_jumpers no)
		(fp_line
			(start -0.7874 0.4064)
			(end -0.7874 -0.4064)
			(stroke
				(width 0.1524)
				(type default)
			)
			(layer "F.SilkS")
		)
		(fp_line
			(start 0.7874 0.4064)
			(end -0.7874 0.4064)
			(stroke
				(width 0.1524)
				(type default)
			)
			(layer "F.SilkS")
		)
		(fp_line
			(start -0.7874 -0.4064)
			(end 0.7874 -0.4064)
			(stroke
				(width 0.1524)
				(type default)
			)
			(layer "F.SilkS")
		)
		(fp_line
			(start 0.7874 -0.4064)
			(end 0.7874 0.4064)
			(stroke
				(width 0.1524)
				(type default)
			)
			(layer "F.SilkS")
		)
		(fp_line
			(start -0.67945 0.3048)
			(end -0.67945 -0.305054)
			(stroke
				(width 0.1)
				(type default)
			)
			(layer "F.Fab")
		)
		(fp_line
			(start -0.12065 0.3048)
			(end -0.67945 0.3048)
			(stroke
				(width 0.1)
				(type default)
			)
			(layer "F.Fab")
		)
		(fp_line
			(start 0.120396 0.3048)
			(end 0.120396 0.2794)
			(stroke
				(width 0.1)
				(type default)
			)
			(layer "F.Fab")
		)
		(fp_line
			(start 0.67945 0.3048)
			(end 0.120396 0.3048)
			(stroke
				(width 0.1)
				(type default)
			)
			(layer "F.Fab")
		)
		(fp_line
			(start -0.12065 0.2794)
			(end -0.12065 0.3048)
			(stroke
				(width 0.1)
				(type default)
			)
			(layer "F.Fab")
		)
		(fp_line
			(start 0.120396 0.2794)
			(end -0.12065 0.2794)
			(stroke
				(width 0.1)
				(type default)
			)
			(layer "F.Fab")
		)
		(fp_line
			(start -0.12065 -0.2794)
			(end 0.12065 -0.2794)
			(stroke
				(width 0.1)
				(type default)
			)
			(layer "F.Fab")
		)
		(fp_line
			(start 0.12065 -0.2794)
			(end 0.12065 -0.3048)
			(stroke
				(width 0.1)
				(type default)
			)
			(layer "F.Fab")
		)
		(fp_line
			(start 0.12065 -0.3048)
			(end 0.67945 -0.3048)
			(stroke
				(width 0.1)
				(type default)
			)
			(layer "F.Fab")
		)
		(fp_line
			(start 0.67945 -0.3048)
			(end 0.67945 0.3048)
			(stroke
				(width 0.1)
				(type default)
			)
			(layer "F.Fab")
		)
		(fp_line
			(start -0.67945 -0.305054)
			(end -0.12065 -0.305054)
			(stroke
				(width 0.1)
				(type default)
			)
			(layer "F.Fab")
		)
		(fp_line
			(start -0.12065 -0.305054)
			(end -0.12065 -0.2794)
			(stroke
				(width 0.1)
				(type default)
			)
			(layer "F.Fab")
		)
		(pad "1" smd circle
			(at -0.40005 0 270)
			(size 0 0)
			(layers "F.Cu" "F.Mask" "F.Paste")
			(net "PVCCIN_CPU0")
		)
		(pad "2" smd circle
			(at 0.40005 0 270)
			(size 0 0)
			(layers "F.Cu" "F.Mask" "F.Paste")
			(net "GND")
		)
	)
)
